# T6G (Grand Teton) — schematic netlist excerpt (pin names and nets, part order shuffled) for the footprints in the layout excerpt that follows; sources: Cadence DE-HDL packaged netlist, KiCad conversion of 04192023_DAF0TMB3IC0_F0TG_MB_C_brd_V02_OCP.brd

H74  HOLE  EMPTY  pkg TH  page 230 : \1\ = NC
R1505  Q_RES  30K 1% CHIP  pkg 0402LF  page 29 : A = PVDD18_S5_P0 ; B = ESPI_CPU0_D2

(kicad_pcb
	(version 20260206)
	(generator "pcbnew")
	(generator_version "10.0")
	(general
		(thickness 1.6)
		(legacy_teardrops no)
	)
	(paper "A4")
	(title_block
		(title "04192023_DAF0TMB3IC0_F0TG_MB_C_brd_V02_OCP.brd")
		(comment 1 "Grand Teton / footprints 4445-4446 of 8354")
	)
	(layers
		(0 "F.Cu" signal "TOP")
		(4 "In1.Cu" signal "GND")
		(6 "In2.Cu" signal "IN1")
		(8 "In3.Cu" signal "GND1")
		(10 "In4.Cu" signal "IN2")
		(12 "In5.Cu" signal "GND2")
		(14 "In6.Cu" signal "IN3")
		(16 "In7.Cu" signal "GND3")
		(18 "In8.Cu" signal "VCC")
		(20 "In9.Cu" signal "VCC1")
		(22 "In10.Cu" signal "GND4")
		(24 "In11.Cu" signal "IN4")
		(26 "In12.Cu" signal "GND5")
		(28 "In13.Cu" signal "IN5")
		(30 "In14.Cu" signal "GND6")
		(32 "In15.Cu" signal "IN6")
		(34 "In16.Cu" signal "GND7")
		(2 "B.Cu" signal "BOTTOM")
		(9 "F.Adhes" user "F.Adhesive")
		(11 "B.Adhes" user "B.Adhesive")
		(13 "F.Paste" user "Package Geometry/Pastemask Top")
		(15 "B.Paste" user "Package Geometry/Pastemask Bottom")
		(5 "F.SilkS" user "Ref Des/Silkscreen Top")
		(7 "B.SilkS" user "Ref Des/Silkscreen Bottom")
		(1 "F.Mask" user "Board Geometry/Soldermask Top")
		(3 "B.Mask" user "Board Geometry/Soldermask Bottom")
		(17 "Dwgs.User" user "User.Drawings")
		(19 "Cmts.User" user "User.Comments")
		(21 "Eco1.User" user "User.Eco1")
		(23 "Eco2.User" user "User.Eco2")
		(25 "Edge.Cuts" user "Board Geometry/Outline")
		(27 "Margin" user)
		(31 "F.CrtYd" user "Package Geometry/Place Bound Top")
		(29 "B.CrtYd" user "Package Geometry/Place Bound Bottom")
		(35 "F.Fab" user "Ref Des/Assembly Top")
		(33 "B.Fab" user "Ref Des/Assembly Bottom")
	)
	(footprint ""
		(layer "F.Cu")
		(at 394.811758 -323.796152 90)
		(property "Reference" "R1505"
			(at 0 0 90)
			(layer "F.SilkS")
			(hide yes)
			(effects
				(font
					(size 1.27 1.27)
				)
			)
		)
		(property "Value" ""
			(at 0 0 90)
			(layer "F.Fab")
			(effects
				(font
					(size 1.27 1.27)
				)
			)
		)
		(duplicate_pad_numbers_are_jumpers no)
		(fp_line
			(start 0.7874 -0.4064)
			(end 0.7874 0.4064)
			(stroke
				(width 0.1524)
				(type default)
			)
			(layer "F.SilkS")
		)
		(fp_line
			(start -0.7874 -0.4064)
			(end 0.7874 -0.4064)
			(stroke
				(width 0.1524)
				(type default)
			)
			(layer "F.SilkS")
		)
		(fp_line
			(start 0.7874 0.4064)
			(end -0.7874 0.4064)
			(stroke
				(width 0.1524)
				(type default)
			)
			(layer "F.SilkS")
		)
		(fp_line
			(start -0.7874 0.4064)
			(end -0.7874 -0.4064)
			(stroke
				(width 0.1524)
				(type default)
			)
			(layer "F.SilkS")
		)
		(fp_line
			(start -0.12065 -0.305054)
			(end -0.12065 -0.2794)
			(stroke
				(width 0.1)
				(type default)
			)
			(layer "F.Fab")
		)
		(fp_line
			(start -0.67945 -0.305054)
			(end -0.12065 -0.305054)
			(stroke
				(width 0.1)
				(type default)
			)
			(layer "F.Fab")
		)
		(fp_line
			(start 0.67945 -0.3048)
			(end 0.67945 0.3048)
			(stroke
				(width 0.1)
				(type default)
			)
			(layer "F.Fab")
		)
		(fp_line
			(start 0.12065 -0.3048)
			(end 0.67945 -0.3048)
			(stroke
				(width 0.1)
				(type default)
			)
			(layer "F.Fab")
		)
		(fp_line
			(start 0.12065 -0.2794)
			(end 0.12065 -0.3048)
			(stroke
				(width 0.1)
				(type default)
			)
			(layer "F.Fab")
		)
		(fp_line
			(start -0.12065 -0.2794)
			(end 0.12065 -0.2794)
			(stroke
				(width 0.1)
				(type default)
			)
			(layer "F.Fab")
		)
		(fp_line
			(start 0.120396 0.2794)
			(end -0.12065 0.2794)
			(stroke
				(width 0.1)
				(type default)
			)
			(layer "F.Fab")
		)
		(fp_line
			(start -0.12065 0.2794)
			(end -0.12065 0.3048)
			(stroke
				(width 0.1)
				(type default)
			)
			(layer "F.Fab")
		)
		(fp_line
			(start 0.67945 0.3048)
			(end 0.120396 0.3048)
			(stroke
				(width 0.1)
				(type default)
			)
			(layer "F.Fab")
		)
		(fp_line
			(start 0.120396 0.3048)
			(end 0.120396 0.2794)
			(stroke
				(width 0.1)
				(type default)
			)
			(layer "F.Fab")
		)
		(fp_line
			(start -0.12065 0.3048)
			(end -0.67945 0.3048)
			(stroke
				(width 0.1)
				(type default)
			)
			(layer "F.Fab")
		)
		(fp_line
			(start -0.67945 0.3048)
			(end -0.67945 -0.305054)
			(stroke
				(width 0.1)
				(type default)
			)
			(layer "F.Fab")
		)
		(pad "1" smd circle
			(at -0.40005 0 90)
			(size 0 0)
			(layers "F.Cu" "F.Mask" "F.Paste")
			(net "PVDD18_S5_P0")
		)
		(pad "2" smd circle
			(at 0.40005 0 90)
			(size 0 0)
			(layers "F.Cu" "F.Mask" "F.Paste")
			(net "ESPI_CPU0_D2")
		)
	)
	(footprint ""
		(layer "F.Cu")
		(at 63.582804 -47.049944 90)
		(property "Reference" "H74"
			(at 0.04826 -7.363968 90)
			(unlocked yes)
			(layer "F.SilkS")
			(effects
				(font
					(size 0.7874 0.5842)
					(thickness 0.1524)
				)
			)
		)
		(property "Value" ""
			(at 0 0 90)
			(layer "F.Fab")
			(effects
				(font
					(size 1.27 1.27)
				)
			)
		)
		(duplicate_pad_numbers_are_jumpers no)
		(pad "" np_thru_hole circle
			(at 0 0 90)
			(size 0 0)
			(drill oval 3.2004 4.8006)
			(layers "*.Cu" "*.Mask")
			(clearance -1.2192)
			(thermal_gap 0.381)
			(padstack
				(mode front_inner_back)
				(layer "Inner"
					(shape oval)
					(size 3.2004 4.8006)
					(clearance 0.381)
				)
				(layer "B.Cu"
					(shape circle)
					(size 0 0)
					(clearance -1.2192)
				)
			)
		)
		(zone
			(layers "F.Cu" "B.Cu" "In1.Cu" "In2.Cu" "In3.Cu" "In4.Cu" "In5.Cu" "In6.Cu"
				"In7.Cu" "In8.Cu" "In9.Cu" "In10.Cu" "In11.Cu" "In12.Cu" "In13.Cu" "In14.Cu"
				"In15.Cu" "In16.Cu"
			)
			(hatch none 0.5)
			(connect_pads
				(clearance 0)
			)
			(min_thickness 0.25)
			(keepout
				(tracks not_allowed)
				(vias allowed)
				(pads allowed)
				(copperpour not_allowed)
				(footprints allowed)
			)
			(placement
				(enabled no)
				(sheetname "")
			)
			(fill
				(thermal_gap 0.5)
				(thermal_bridge_width 0.5)
				(island_removal_mode 0)
			)
			(polygon
				(pts
					(arc
						(start 64.382904 -49.158144)
						(mid 66.491104 -47.049944)
						(end 64.382904 -44.941744)
					)
					(arc
						(start 62.782704 -44.941744)
						(mid 60.674504 -47.049944)
						(end 62.782704 -49.158144)
					)
				)
			)
		)
		(zone
			(layers "F.Cu" "B.Cu" "In1.Cu" "In2.Cu" "In3.Cu" "In4.Cu" "In5.Cu" "In6.Cu"
				"In7.Cu" "In8.Cu" "In9.Cu" "In10.Cu" "In11.Cu" "In12.Cu" "In13.Cu" "In14.Cu"
				"In15.Cu" "In16.Cu"
			)
			(hatch none 0.5)
			(connect_pads
				(clearance 0)
			)
			(min_thickness 0.25)
			(keepout
				(tracks not_allowed)
				(vias allowed)
				(pads allowed)
				(copperpour not_allowed)
				(footprints allowed)
			)
			(placement
				(enabled no)
				(sheetname "")
			)
			(fill
				(thermal_gap 0.5)
				(thermal_bridge_width 0.5)
				(island_removal_mode 0)
			)
			(polygon
				(pts
					(arc
						(start 64.382904 -50.050192)
						(mid 67.383152 -47.049944)
						(end 64.382904 -44.049696)
					)
					(arc
						(start 62.782704 -44.049696)
						(mid 59.782456 -47.049944)
						(end 62.782704 -50.050192)
					)
				)
			)
		)
	)
)
